FILE_TYPE = CONNECTIVITY;
{Allegro Design Entry HDL 16.6-p007 (v16-6-112F) 10/10/2012}
"PAGE_NUMBER" = 87;
0"NC";
1"M_M_DQS_DP<17:0>";
2"M_M_DQS_DN<17:0>";
3"M_M_DQ<63:0>";
4"M_M_MA<17:0>";
5"M_M_CS_N<7:0>";
6"M_M_CLK_DN<3:0>";
7"M_M_CLK_DP<3:0>";
8"M_M_BA<1:0>";
9"M_M_ECC<7:0>";
10"M_M_CKE<3:0>";
11"M_M_BG<1:0>";
12"M_M_ODT<3:0>";
13"PVDDQ_KLM\g";
14"GND\g";
15"GND\g";
16"GND\g";
17"PVPP_KLM\g";
18"PVPP_KLM\g";
19"P12V_NVDIMM_KLM\g";
20"GND\g";
21"PVTT_KLM\g";
22"TP_CH_M_DIMM_M0_RFU_2";
23"M_M_MA<17>";
24"M_M_MA<16>";
25"M_M_MA<15>";
26"M_M_MA<13>";
27"M_M_DQ<38>";
28"M_M_VREF";
29"TP_CH_M_DIMM_M0_RFU_1";
30"TP_CH_M_DIMM_M0_RFU_0";
31"SMB_DDR_KLM_VPP_SDA";
32"SMB_DDR_KLM_VPP_SCL";
33"FM_ADR_COMPLETE_KLM_N";
34"M_KLM_RST_N";
35"M_M_PAR";
36"FM_DIMM_EVENT_COD_N";
37"M_M_C<2>";
38"M_M_CS_N<0>";
39"M_M_CKE<0>";
40"M_M_ODT<1>";
41"M_M_ODT<0>";
42"M_M_ECC<6>";
43"M_M_BA<0>";
44"M_M_BG<1>";
45"M_M_BG<0>";
46"M_M_CLK_DP<1>";
47"M_M_CKE<1>";
48"M_M_ECC<1>";
49"M_M_ECC<0>";
50"M_M_ECC<3>";
51"M_M_ECC<2>";
52"M_M_ECC<5>";
53"M_M_ECC<4>";
54"M_M_ECC<7>";
55"M_M_MA<0>";
56"M_M_CS_N<1>";
57"M_M_CS_N<2>";
58"M_M_BA<1>";
59"M_M_CLK_DN<0>";
60"M_M_CLK_DP<0>";
61"M_M_CLK_DN<1>";
62"M_M_CS_N<3>";
63"M_M_ALERT_N";
64"M_M_ACT_N";
65"M_M_DQ<1>";
66"M_M_DQ<4>";
67"M_M_DQ<5>";
68"M_M_DQ<2>";
69"M_M_DQ<3>";
70"M_M_DQ<0>";
71"M_M_DQ<7>";
72"M_M_DQ<6>";
73"M_M_DQ<9>";
74"M_M_DQ<8>";
75"M_M_DQ<10>";
76"M_M_DQ<11>";
77"M_M_DQ<14>";
78"M_M_DQ<12>";
79"M_M_DQ<15>";
80"M_M_DQ<17>";
81"M_M_DQ<13>";
82"M_M_DQ<16>";
83"M_M_DQ<19>";
84"M_M_DQ<18>";
85"M_M_DQ<21>";
86"M_M_DQ<20>";
87"M_M_DQ<27>";
88"M_M_DQ<23>";
89"M_M_DQ<22>";
90"M_M_DQ<25>";
91"M_M_DQ<24>";
92"M_M_DQ<26>";
93"M_M_DQ<31>";
94"M_M_DQ<30>";
95"M_M_DQ<29>";
96"M_M_DQ<28>";
97"M_M_DQ<37>";
98"M_M_DQ<34>";
99"M_M_DQ<33>";
100"M_M_DQ<32>";
101"M_M_DQ<35>";
102"M_M_DQ<39>";
103"M_M_DQ<36>";
104"M_M_DQ<41>";
105"M_M_DQ<40>";
106"M_M_DQ<43>";
107"M_M_DQ<42>";
108"M_M_DQ<45>";
109"M_M_DQ<44>";
110"M_M_DQ<47>";
111"M_M_MA<14>";
112"M_M_MA<11>";
113"M_M_MA<10>";
114"M_M_MA<2>";
115"M_M_MA<9>";
116"M_M_MA<8>";
117"M_M_MA<7>";
118"M_M_MA<6>";
119"M_M_MA<5>";
120"M_M_MA<4>";
121"M_M_MA<3>";
122"M_M_MA<12>";
123"M_M_MA<1>";
124"M_M_DQ<46>";
125"M_M_DQ<49>";
126"M_M_DQ<48>";
127"M_M_DQ<51>";
128"M_M_DQ<50>";
129"M_M_DQ<53>";
130"M_M_DQ<52>";
131"M_M_DQ<55>";
132"M_M_DQ<56>";
133"M_M_DQ<54>";
134"M_M_DQ<57>";
135"M_M_DQ<63>";
136"M_M_DQ<60>";
137"M_M_DQ<59>";
138"M_M_DQ<58>";
139"M_M_DQ<61>";
140"M_M_DQ<62>";
141"M_M_DQS_DP<6>";
142"M_M_DQS_DN<6>";
143"M_M_DQS_DP<5>";
144"M_M_DQS_DN<5>";
145"M_M_DQS_DP<4>";
146"M_M_DQS_DN<4>";
147"M_M_DQS_DP<3>";
148"M_M_DQS_DN<3>";
149"M_M_DQS_DP<2>";
150"M_M_DQS_DN<2>";
151"M_M_DQS_DP<1>";
152"M_M_DQS_DN<1>";
153"M_M_DQS_DP<0>";
154"M_M_DQS_DN<0>";
155"M_M_DQS_DP<9>";
156"M_M_DQS_DN<9>";
157"M_M_DQS_DP<8>";
158"M_M_DQS_DN<8>";
159"M_M_DQS_DP<7>";
160"M_M_DQS_DN<7>";
161"M_M_DQS_DN<17>";
162"M_M_DQS_DP<16>";
163"M_M_DQS_DN<16>";
164"M_M_DQS_DP<15>";
165"M_M_DQS_DN<15>";
166"M_M_DQS_DP<14>";
167"M_M_DQS_DN<14>";
168"M_M_DQS_DP<13>";
169"M_M_DQS_DN<13>";
170"M_M_DQS_DP<12>";
171"M_M_DQS_DN<12>";
172"M_M_DQS_DP<11>";
173"M_M_DQS_DN<11>";
174"M_M_DQS_DP<10>";
175"M_M_DQS_DN<10>";
176"M_M_DQS_DP<17>";
%"TAP"
"6","(-1750,2200)","2","mstr_standard","I100";
;
CDS_LIB"mstr_standard"
BODY_TYPE"PLUMBING"
HDL_TAP"TRUE";
"B \NAC \NWC"3;
"S \NAC"
BN"8"74;
%"TAP"
"6","(-1750,2300)","2","mstr_standard","I101";
;
CDS_LIB"mstr_standard"
BODY_TYPE"PLUMBING"
HDL_TAP"TRUE";
"B \NAC \NWC"3;
"S \NAC"
BN"10"75;
%"TAP"
"6","(-1750,2350)","2","mstr_standard","I102";
;
CDS_LIB"mstr_standard"
BODY_TYPE"PLUMBING"
HDL_TAP"TRUE";
"B \NAC \NWC"3;
"S \NAC"
BN"13"81;
%"TAP"
"6","(-1750,2100)","2","mstr_standard","I103";
;
CDS_LIB"mstr_standard"
BODY_TYPE"PLUMBING"
HDL_TAP"TRUE";
"B \NAC \NWC"3;
"S \NAC"
BN"6"72;
%"TAP"
"6","(-1750,2050)","2","mstr_standard","I104";
;
CDS_LIB"mstr_standard"
BODY_TYPE"PLUMBING"
HDL_TAP"TRUE";
"B \NAC \NWC"3;
"S \NAC"
BN"7"71;
%"TAP"
"6","(-1750,2000)","2","mstr_standard","I105";
;
CDS_LIB"mstr_standard"
BODY_TYPE"PLUMBING"
HDL_TAP"TRUE";
"B \NAC \NWC"3;
"S \NAC"
BN"4"66;
%"TAP"
"6","(-1750,1950)","2","mstr_standard","I106";
;
CDS_LIB"mstr_standard"
BODY_TYPE"PLUMBING"
HDL_TAP"TRUE";
"B \NAC \NWC"3;
"S \NAC"
BN"5"67;
%"TAP"
"6","(-1750,1900)","2","mstr_standard","I107";
;
CDS_LIB"mstr_standard"
BODY_TYPE"PLUMBING"
HDL_TAP"TRUE";
"B \NAC \NWC"3;
"S \NAC"
BN"2"68;
%"TAP"
"6","(-1750,1750)","2","mstr_standard","I108";
;
CDS_LIB"mstr_standard"
BODY_TYPE"PLUMBING"
HDL_TAP"TRUE";
"B \NAC \NWC"3;
"S \NAC"
BN"1"65;
%"TAP"
"6","(-1750,1850)","2","mstr_standard","I109";
;
CDS_LIB"mstr_standard"
BODY_TYPE"PLUMBING"
HDL_TAP"TRUE";
"B \NAC \NWC"3;
"S \NAC"
BN"3"69;
%"PVDDQ_KLM"
"1","(-1450,2600)","0","mstr_symbols","I11";
;
VOLTAGE"1.2V"
BOM_COST"MEM"
CDS_LIB"mstr_symbols"
BODY_TYPE"PLUMBING"
ROOM"DDR4_CH_D"
HDL_POWER"PVDDQ_KLM";
"G\NAC"13;
%"TAP"
"6","(-1750,1800)","2","mstr_standard","I110";
;
CDS_LIB"mstr_standard"
BODY_TYPE"PLUMBING"
HDL_TAP"TRUE";
"B \NAC \NWC"3;
"S \NAC"
BN"0"70;
%"TAP"
"6","(-3250,4850)","0","mstr_standard","I112";
;
CDS_LIB"mstr_standard"
BODY_TYPE"PLUMBING"
HDL_TAP"TRUE";
"B \NAC \NWC"4;
"S \NAC"
BN"16"24;
%"TAP"
"6","(-3250,4900)","0","mstr_standard","I113";
;
CDS_LIB"mstr_standard"
BODY_TYPE"PLUMBING"
HDL_TAP"TRUE";
"B \NAC \NWC"4;
"S \NAC"
BN"17"23;
%"TAP"
"6","(-3250,4800)","0","mstr_standard","I114";
;
CDS_LIB"mstr_standard"
BODY_TYPE"PLUMBING"
HDL_TAP"TRUE";
"B \NAC \NWC"4;
"S \NAC"
BN"15"25;
%"TAP"
"6","(-3250,4750)","0","mstr_standard","I115";
;
CDS_LIB"mstr_standard"
BODY_TYPE"PLUMBING"
HDL_TAP"TRUE";
"B \NAC \NWC"4;
"S \NAC"
BN"14"111;
%"TAP"
"6","(-3250,4700)","0","mstr_standard","I116";
;
CDS_LIB"mstr_standard"
BODY_TYPE"PLUMBING"
HDL_TAP"TRUE";
"B \NAC \NWC"4;
"S \NAC"
BN"13"26;
%"TAP"
"6","(-3250,4650)","0","mstr_standard","I117";
;
CDS_LIB"mstr_standard"
BODY_TYPE"PLUMBING"
HDL_TAP"TRUE";
"B \NAC \NWC"4;
"S \NAC"
BN"12"122;
%"TAP"
"6","(-3250,4600)","0","mstr_standard","I118";
;
CDS_LIB"mstr_standard"
BODY_TYPE"PLUMBING"
HDL_TAP"TRUE";
"B \NAC \NWC"4;
"S \NAC"
BN"11"112;
%"TAP"
"6","(-3250,4550)","0","mstr_standard","I119";
;
CDS_LIB"mstr_standard"
BODY_TYPE"PLUMBING"
HDL_TAP"TRUE";
"B \NAC \NWC"4;
"S \NAC"
BN"10"113;
%"TAP"
"6","(900,4500)","2","mstr_standard","I12";
;
CDS_LIB"mstr_standard"
BODY_TYPE"PLUMBING"
HDL_TAP"TRUE";
"B \NAC \NWC"2;
"S \NAC"
BN"11"173;
%"TAP"
"6","(-3250,4450)","0","mstr_standard","I120";
;
CDS_LIB"mstr_standard"
BODY_TYPE"PLUMBING"
HDL_TAP"TRUE";
"B \NAC \NWC"4;
"S \NAC"
BN"8"116;
%"TAP"
"6","(-3250,4500)","0","mstr_standard","I121";
;
CDS_LIB"mstr_standard"
BODY_TYPE"PLUMBING"
HDL_TAP"TRUE";
"B \NAC \NWC"4;
"S \NAC"
BN"9"115;
%"TAP"
"6","(-3250,4400)","0","mstr_standard","I122";
;
CDS_LIB"mstr_standard"
BODY_TYPE"PLUMBING"
HDL_TAP"TRUE";
"B \NAC \NWC"4;
"S \NAC"
BN"7"117;
%"TAP"
"6","(-3250,4350)","0","mstr_standard","I123";
;
CDS_LIB"mstr_standard"
BODY_TYPE"PLUMBING"
HDL_TAP"TRUE";
"B \NAC \NWC"4;
"S \NAC"
BN"6"118;
%"TAP"
"6","(-3250,4300)","0","mstr_standard","I124";
;
CDS_LIB"mstr_standard"
BODY_TYPE"PLUMBING"
HDL_TAP"TRUE";
"B \NAC \NWC"4;
"S \NAC"
BN"5"119;
%"TAP"
"6","(-3250,4250)","0","mstr_standard","I125";
;
CDS_LIB"mstr_standard"
BODY_TYPE"PLUMBING"
HDL_TAP"TRUE";
"B \NAC \NWC"4;
"S \NAC"
BN"4"120;
%"TAP"
"6","(-3250,4200)","0","mstr_standard","I126";
;
CDS_LIB"mstr_standard"
BODY_TYPE"PLUMBING"
HDL_TAP"TRUE";
"B \NAC \NWC"4;
"S \NAC"
BN"3"121;
%"TAP"
"6","(-3250,4150)","0","mstr_standard","I127";
;
CDS_LIB"mstr_standard"
BODY_TYPE"PLUMBING"
HDL_TAP"TRUE";
"B \NAC \NWC"4;
"S \NAC"
BN"2"114;
%"TAP"
"6","(-3250,4100)","0","mstr_standard","I128";
;
CDS_LIB"mstr_standard"
BODY_TYPE"PLUMBING"
HDL_TAP"TRUE";
"B \NAC \NWC"4;
"S \NAC"
BN"1"123;
%"TAP"
"6","(-3250,4050)","0","mstr_standard","I129";
;
CDS_LIB"mstr_standard"
BODY_TYPE"PLUMBING"
HDL_TAP"TRUE";
"B \NAC \NWC"4;
"S \NAC"
BN"0"55;
%"TAP"
"6","(900,4400)","2","mstr_standard","I13";
;
CDS_LIB"mstr_standard"
BODY_TYPE"PLUMBING"
HDL_TAP"TRUE";
"B \NAC \NWC"2;
"S \NAC"
BN"10"175;
%"TAP"
"6","(-3250,3950)","0","mstr_standard","I130";
;
CDS_LIB"mstr_standard"
BODY_TYPE"PLUMBING"
HDL_TAP"TRUE";
"B \NAC \NWC"8;
"S \NAC"
BN"1"58;
%"TAP"
"6","(-3250,3900)","0","mstr_standard","I133";
;
CDS_LIB"mstr_standard"
BODY_TYPE"PLUMBING"
HDL_TAP"TRUE";
"B \NAC \NWC"8;
"S \NAC"
BN"0"43;
%"TAP"
"6","(-3250,3800)","0","mstr_standard","I134";
;
CDS_LIB"mstr_standard"
BODY_TYPE"PLUMBING"
HDL_TAP"TRUE";
"B \NAC \NWC"11;
"S \NAC"
BN"0"45;
%"TAP"
"6","(-3250,3850)","0","mstr_standard","I135";
;
CDS_LIB"mstr_standard"
BODY_TYPE"PLUMBING"
HDL_TAP"TRUE";
"B \NAC \NWC"11;
"S \NAC"
BN"1"44;
%"TAP"
"6","(-3250,2800)","0","mstr_standard","I138";
;
CDS_LIB"mstr_standard"
BODY_TYPE"PLUMBING"
HDL_TAP"TRUE";
"B \NAC \NWC"9;
"S \NAC"
BN"7"54;
%"TAP"
"6","(-3250,2850)","0","mstr_standard","I139";
;
CDS_LIB"mstr_standard"
BODY_TYPE"PLUMBING"
HDL_TAP"TRUE";
"B \NAC \NWC"9;
"S \NAC"
BN"6"42;
%"TAP"
"6","(900,4300)","2","mstr_standard","I14";
;
CDS_LIB"mstr_standard"
BODY_TYPE"PLUMBING"
HDL_TAP"TRUE";
"B \NAC \NWC"2;
"S \NAC"
BN"9"156;
%"TAP"
"6","(-3250,2750)","0","mstr_standard","I140";
;
CDS_LIB"mstr_standard"
BODY_TYPE"PLUMBING"
HDL_TAP"TRUE";
"B \NAC \NWC"9;
"S \NAC"
BN"4"53;
%"TAP"
"6","(-3250,2700)","0","mstr_standard","I141";
;
CDS_LIB"mstr_standard"
BODY_TYPE"PLUMBING"
HDL_TAP"TRUE";
"B \NAC \NWC"9;
"S \NAC"
BN"5"52;
%"TAP"
"6","(-3250,2650)","0","mstr_standard","I142";
;
CDS_LIB"mstr_standard"
BODY_TYPE"PLUMBING"
HDL_TAP"TRUE";
"B \NAC \NWC"9;
"S \NAC"
BN"2"51;
%"TAP"
"6","(-3250,2600)","0","mstr_standard","I143";
;
CDS_LIB"mstr_standard"
BODY_TYPE"PLUMBING"
HDL_TAP"TRUE";
"B \NAC \NWC"9;
"S \NAC"
BN"3"50;
%"TAP"
"6","(-3250,2550)","0","mstr_standard","I144";
;
CDS_LIB"mstr_standard"
BODY_TYPE"PLUMBING"
HDL_TAP"TRUE";
"B \NAC \NWC"9;
"S \NAC"
BN"0"49;
%"TAP"
"6","(-3250,2500)","0","mstr_standard","I145";
;
CDS_LIB"mstr_standard"
BODY_TYPE"PLUMBING"
HDL_TAP"TRUE";
"B \NAC \NWC"9;
"S \NAC"
BN"1"48;
%"TAP"
"6","(900,4200)","2","mstr_standard","I15";
;
CDS_LIB"mstr_standard"
BODY_TYPE"PLUMBING"
HDL_TAP"TRUE";
"B \NAC \NWC"2;
"S \NAC"
BN"8"158;
%"TAP"
"6","(-3250,3700)","0","mstr_standard","I152";
;
CDS_LIB"mstr_standard"
BODY_TYPE"PLUMBING"
HDL_TAP"TRUE";
"B \NAC \NWC"7;
"S \NAC"
BN"1"46;
%"TAP"
"6","(-3250,3600)","0","mstr_standard","I153";
;
CDS_LIB"mstr_standard"
BODY_TYPE"PLUMBING"
HDL_TAP"TRUE";
"B \NAC \NWC"7;
"S \NAC"
BN"0"60;
%"TAP"
"6","(-3450,3650)","0","mstr_standard","I154";
;
CDS_LIB"mstr_standard"
BODY_TYPE"PLUMBING"
HDL_TAP"TRUE";
"B \NAC \NWC"6;
"S \NAC"
BN"1"61;
%"TAP"
"6","(-3450,3550)","0","mstr_standard","I155";
;
CDS_LIB"mstr_standard"
BODY_TYPE"PLUMBING"
HDL_TAP"TRUE";
"B \NAC \NWC"6;
"S \NAC"
BN"0"59;
%"TAP"
"6","(-3250,3400)","0","mstr_standard","I158";
;
CDS_LIB"mstr_standard"
BODY_TYPE"PLUMBING"
HDL_TAP"TRUE";
"B \NAC \NWC"5;
"S \NAC"
BN"3"62;
%"TAP"
"6","(-3250,3350)","0","mstr_standard","I159";
;
CDS_LIB"mstr_standard"
BODY_TYPE"PLUMBING"
HDL_TAP"TRUE";
"B \NAC \NWC"5;
"S \NAC"
BN"2"57;
%"TAP"
"6","(900,4100)","2","mstr_standard","I16";
;
CDS_LIB"mstr_standard"
BODY_TYPE"PLUMBING"
HDL_TAP"TRUE";
"B \NAC \NWC"2;
"S \NAC"
BN"7"160;
%"TAP"
"6","(-3250,3300)","0","mstr_standard","I160";
;
CDS_LIB"mstr_standard"
BODY_TYPE"PLUMBING"
HDL_TAP"TRUE";
"B \NAC \NWC"5;
"S \NAC"
BN"1"56;
%"TAP"
"6","(-3250,3250)","0","mstr_standard","I161";
;
CDS_LIB"mstr_standard"
BODY_TYPE"PLUMBING"
HDL_TAP"TRUE";
"B \NAC \NWC"5;
"S \NAC"
BN"0"38;
%"TAP"
"6","(-3250,3150)","0","mstr_standard","I163";
;
CDS_LIB"mstr_standard"
BODY_TYPE"PLUMBING"
HDL_TAP"TRUE";
"B \NAC \NWC"10;
"S \NAC"
BN"1"47;
%"TAP"
"6","(-3250,3100)","0","mstr_standard","I164";
;
CDS_LIB"mstr_standard"
BODY_TYPE"PLUMBING"
HDL_TAP"TRUE";
"B \NAC \NWC"10;
"S \NAC"
BN"0"39;
%"TAP"
"6","(-3250,3000)","0","mstr_standard","I165";
;
CDS_LIB"mstr_standard"
BODY_TYPE"PLUMBING"
HDL_TAP"TRUE";
"B \NAC \NWC"12;
"S \NAC"
BN"1"40;
%"TAP"
"6","(-3250,2950)","0","mstr_standard","I166";
;
CDS_LIB"mstr_standard"
BODY_TYPE"PLUMBING"
HDL_TAP"TRUE";
"B \NAC \NWC"12;
"S \NAC"
BN"0"41;
%"SCONN288_H44441004"
"4","(-400,2050)","0","mstr_sconn","I169";
;
CDS_SEC"4"
LOCATION"J1A1"
PART_NUMBER"H44441-004"
MATERIAL"SCONN"
PACK_TYPE"PIP"
BOM_COST"MEM"
CDS_LIB"mstr_sconn"
SEC_TYPE"PIP"
SEC"4"
CDS_LOCATION"J1A1"
ROOM"DDR4_CH_M";
"VPP<4>"
$PN"142"17;
"VTT<1>"
$PN"77"21;
"VPP<0>"
$PN"287"17;
"VPP<1>"
$PN"286"17;
"VPP<2>"
$PN"288"17;
"VPP<3>"
$PN"143"17;
"VDD<1>"
$PN"233"13;
"VDD<2>"
$PN"231"13;
"VDD<3>"
$PN"229"13;
"VDD<4>"
$PN"226"13;
"VDD<5>"
$PN"223"13;
"VDD<7>"
$PN"217"13;
"VDD<8>"
$PN"215"13;
"VDD<9>"
$PN"212"13;
"VDD<11>"
$PN"206"13;
"VDD<12>"
$PN"204"13;
"VDD<14>"
$PN"90"13;
"VDD<15>"
$PN"88"13;
"VDD<17>"
$PN"83"13;
"VDD<18>"
$PN"80"13;
"VDD<20>"
$PN"73"13;
"VDD<21>"
$PN"70"13;
"VDD<22>"
$PN"67"13;
"VDD<24>"
$PN"61"13;
"12V<0>"
$PN"145"19;
"12V<1>"
$PN"1"19;
"VTT<0>"
$PN"221"21;
"VDD<25>"
$PN"59"13;
"VDD<23>"
$PN"64"13;
"VDD<19>"
$PN"76"13;
"VDD<16>"
$PN"85"13;
"VDD<13>"
$PN"92"13;
"VDD<10>"
$PN"209"13;
"VDD<6>"
$PN"220"13;
"VDD<0>"
$PN"236"13;
%"TAP"
"6","(900,4000)","2","mstr_standard","I17";
;
CDS_LIB"mstr_standard"
BODY_TYPE"PLUMBING"
HDL_TAP"TRUE";
"B \NAC \NWC"2;
"S \NAC"
BN"6"142;
%"GND"
"1","(2500,1150)","2","mstr_symbols","I170";
;
VOLTAGE"0"
BOM_COST"MEM"
CDS_LIB"mstr_symbols"
SIZE"1B"
BODY_TYPE"PLUMBING"
ROOM"DDR4_CH_D"
HDL_POWER"GND";
"A\NAC"14;
%"GND"
"1","(-5000,1850)","2","mstr_symbols","I176";
;
VOLTAGE"0"
BOM_COST"MEM"
CDS_LIB"mstr_symbols"
SIZE"1B"
BODY_TYPE"PLUMBING"
ROOM"DDR4_CH_D"
HDL_POWER"GND";
"A\NAC"15;
%"GND"
"1","(-4650,1300)","0","mstr_symbols","I177";
;
VOLTAGE"16V"
CDS_LIB"mstr_symbols"
BOM_COST"MEM"
SIZE"1B"
BODY_TYPE"PLUMBING"
ROOM"DDR4_CH_M1"
HDL_POWER"GND";
"A\NAC"16;
%"CAP_A"
"1","(-4650,1550)","2","dev_discrete","I178";
;
LOCATION"C1A5"
PART_NUMBER"A36096-045"
VALUE"0.01UF"
TOLERANCE"10%"
PACK_TYPE"0402V"
VOLTAGE"25V"
MATERIAL"X7R"
CDS_LOCATION"C1A5"
BOM_COST"MEM"
CDS_LIB"dev_discrete"
CDS_SEC"1"
SEC_TYPE"0402V"
SEC"1"
ROOM"DDR4_CH_M";
"B"
$PN"2"16;
"A"
$PN"1"28;
%"PVPP_KLM"
"1","(-1100,3050)","0","mstr_symbols","I179";
;
VOLTAGE"2.5V"
BOM_COST"MEM"
CDS_LIB"mstr_symbols"
BODY_TYPE"PLUMBING"
ROOM"DDR4_CH_D"
HDL_POWER"PVPP_KLM";
"G\NAC"17;
%"TAP"
"6","(900,3900)","2","mstr_standard","I18";
;
CDS_LIB"mstr_standard"
BODY_TYPE"PLUMBING"
HDL_TAP"TRUE";
"B \NAC \NWC"2;
"S \NAC"
BN"5"144;
%"PVPP_KLM"
"1","(-5000,2250)","0","mstr_symbols","I180";
;
VOLTAGE"2.5V"
BOM_COST"MEM"
CDS_LIB"mstr_symbols"
BODY_TYPE"PLUMBING"
ROOM"DDR4_CH_D"
HDL_POWER"PVPP_KLM";
"G\NAC"18;
%"SCONN288_H44441004"
"3","(1800,2450)","0","mstr_sconn","I185";
;
CDS_SEC"3"
PART_NUMBER"H44441-004"
MATERIAL"SCONN"
LOCATION"J1A1"
PACK_TYPE"PIP"
BOM_COST"MEM"
CDS_LIB"mstr_sconn"
SEC_TYPE"PIP"
SEC"3"
CDS_LOCATION"J1A1"
ROOM"DDR4_CH_M";
"VSS<93>"
$PN"2"20;
"VSS<92>"
$PN"4"20;
"VSS<91>"
$PN"6"20;
"VSS<90>"
$PN"9"20;
"VSS<89>"
$PN"11"20;
"VSS<88>"
$PN"13"20;
"VSS<0>"
$PN"283"14;
"VSS<1>"
$PN"281"14;
"VSS<2>"
$PN"279"14;
"VSS<3>"
$PN"276"14;
"VSS<4>"
$PN"274"14;
"VSS<5>"
$PN"272"14;
"VSS<6>"
$PN"270"14;
"VSS<7>"
$PN"268"14;
"VSS<8>"
$PN"265"14;
"VSS<9>"
$PN"263"14;
"VSS<10>"
$PN"261"14;
"VSS<11>"
$PN"259"14;
"VSS<12>"
$PN"257"14;
"VSS<13>"
$PN"254"14;
"VSS<14>"
$PN"252"14;
"VSS<15>"
$PN"250"14;
"VSS<16>"
$PN"248"14;
"VSS<17>"
$PN"246"14;
"VSS<18>"
$PN"243"14;
"VSS<19>"
$PN"241"14;
"VSS<20>"
$PN"239"14;
"VSS<21>"
$PN"202"14;
"VSS<22>"
$PN"200"14;
"VSS<23>"
$PN"198"14;
"VSS<24>"
$PN"195"14;
"VSS<25>"
$PN"193"14;
"VSS<26>"
$PN"191"14;
"VSS<27>"
$PN"189"14;
"VSS<28>"
$PN"187"14;
"VSS<29>"
$PN"184"14;
"VSS<30>"
$PN"182"14;
"VSS<31>"
$PN"180"14;
"VSS<32>"
$PN"178"14;
"VSS<33>"
$PN"176"14;
"VSS<34>"
$PN"173"14;
"VSS<35>"
$PN"171"14;
"VSS<36>"
$PN"169"14;
"VSS<37>"
$PN"167"14;
"VSS<38>"
$PN"165"14;
"VSS<39>"
$PN"162"14;
"VSS<40>"
$PN"160"14;
"VSS<41>"
$PN"158"14;
"VSS<42>"
$PN"156"14;
"VSS<43>"
$PN"154"14;
"VSS<44>"
$PN"151"14;
"VSS<47>"
$PN"138"20;
"VSS<48>"
$PN"136"20;
"VSS<49>"
$PN"134"20;
"VSS<50>"
$PN"131"20;
"VSS<51>"
$PN"129"20;
"VSS<52>"
$PN"127"20;
"VSS<53>"
$PN"125"20;
"VSS<54>"
$PN"123"20;
"VSS<55>"
$PN"120"20;
"VSS<56>"
$PN"118"20;
"VSS<57>"
$PN"116"20;
"VSS<58>"
$PN"114"20;
"VSS<59>"
$PN"112"20;
"VSS<60>"
$PN"109"20;
"VSS<61>"
$PN"107"20;
"VSS<62>"
$PN"105"20;
"VSS<63>"
$PN"103"20;
"VSS<64>"
$PN"101"20;
"VSS<65>"
$PN"98"20;
"VSS<66>"
$PN"96"20;
"VSS<67>"
$PN"94"20;
"VSS<68>"
$PN"57"20;
"VSS<69>"
$PN"55"20;
"VSS<70>"
$PN"53"20;
"VSS<71>"
$PN"50"20;
"VSS<72>"
$PN"48"20;
"VSS<73>"
$PN"46"20;
"VSS<74>"
$PN"44"20;
"VSS<75>"
$PN"42"20;
"VSS<76>"
$PN"39"20;
"VSS<77>"
$PN"37"20;
"VSS<78>"
$PN"35"20;
"VSS<79>"
$PN"33"20;
"VSS<80>"
$PN"31"20;
"VSS<81>"
$PN"28"20;
"VSS<82>"
$PN"26"20;
"VSS<83>"
$PN"24"20;
"VSS<84>"
$PN"22"20;
"VSS<85>"
$PN"20"20;
"VSS<86>"
$PN"17"20;
"VSS<87>"
$PN"15"20;
"VSS<45>"
$PN"149"14;
"VSS<46>"
$PN"147"14;
%"SCONN288_H44441004"
"1","(-2500,3250)","0","mstr_sconn","I186";
;
CDS_SEC"1"
PART_NUMBER"H44441-004"
MATERIAL"SCONN"
LOCATION"J1A1"
PACK_TYPE"PIP"
BOM_COST"MEM"
CDS_LIB"mstr_sconn"
SEC_TYPE"PIP"
SEC"1"
CDS_LOCATION"J1A1"
ROOM"DDR4_CH_M";
"DQ<63>"
$PN"280"140;
"DQ<62>"
$PN"135"135;
"DQ<61>"
$PN"273"136;
"DQ<5>"
$PN"148"66;
"DQ<4>"
$PN"3"67;
"DQ<3>"
$PN"157"68;
"DQ<2>"
$PN"12"69;
"DQ<47>"
$PN"258"124;
"DQ<48>"
$PN"119"125;
"DQ<49>"
$PN"264"126;
"DQ<50>"
$PN"126"127;
"DQ<51>"
$PN"271"128;
"DQ<52>"
$PN"117"129;
"DQ<53>"
$PN"262"130;
"DQ<54>"
$PN"124"131;
"DQ<58>"
$PN"137"137;
"DQ<57>"
$PN"275"132;
"SAVE_N_NC"
$PN"230"33;
"RFU<1>"
$PN"227"29;
"RFU<0>"
$PN"205"30;
"DQ<17>"
$PN"172"82;
"DQ<15>"
$PN"166"77;
"DQ<26>"
$PN"45"87;
"DQ<27>"
$PN"190"92;
"S0_N"
$PN"84"38;
"CKE<0>"
$PN"60"39;
"ODT<1>"
$PN"91"40;
"ODT<0>"
$PN"87"41;
"CB<7>"
$PN"199"42;
"A16_RAS_N"
$PN"82"24;
"A15_CAS_N"
$PN"86"25;
"A14_WE_N"
$PN"228"111;
"A11"
$PN"210"112;
"A10"
$PN"225"113;
"DQ<38>"
$PN"102"102;
"DQ<36>"
$PN"95"97;
"DQ<35>"
$PN"249"98;
"A2"
$PN"216"114;
"ALERT_N"
$PN"208"63;
"ACT_N"
$PN"62"64;
"DQ<0>"
$PN"5"65;
"DQ<1>"
$PN"150"70;
"SA<1>"
$PN"140"15;
"SA<2>"
$PN"238"18;
"VDDSPD"
$PN"284"18;
"SA<0>"
$PN"139"15;
"BA<0>"
$PN"81"43;
"BG<1>"
$PN"207"44;
"BG<0>"
$PN"63"45;
"CK1P"
$PN"218"46;
"VREFCA"
$PN"146"28;
"SDA"
$PN"285"31;
"SCL"
$PN"141"32;
"RFU<2>"
$PN"144"22;
"RESET_N"
$PN"58"34;
"PAR"
$PN"222"35;
"EVENT_N"
$PN"78"36;
"DQ<6>"
$PN"10"71;
"DQ<7>"
$PN"155"72;
"DQ<8>"
$PN"16"73;
"DQ<9>"
$PN"161"74;
"DQ<10>"
$PN"23"76;
"DQ<11>"
$PN"168"75;
"DQ<12>"
$PN"14"81;
"DQ<13>"
$PN"159"78;
"DQ<14>"
$PN"21"79;
"DQ<16>"
$PN"27"80;
"DQ<18>"
$PN"34"83;
"DQ<19>"
$PN"179"84;
"DQ<20>"
$PN"25"85;
"DQ<21>"
$PN"170"86;
"DQ<22>"
$PN"32"88;
"DQ<23>"
$PN"177"89;
"DQ<24>"
$PN"38"90;
"DQ<25>"
$PN"183"91;
"DQ<30>"
$PN"43"93;
"DQ<31>"
$PN"188"94;
"DQ<32>"
$PN"97"99;
"DQ<33>"
$PN"242"100;
"DQ<34>"
$PN"104"101;
"DQ<37>"
$PN"240"103;
"DQ<39>"
$PN"247"27;
"DQ<40>"
$PN"108"104;
"DQ<41>"
$PN"253"105;
"DQ<42>"
$PN"115"106;
"DQ<43>"
$PN"260"107;
"DQ<44>"
$PN"106"108;
"DQ<45>"
$PN"251"109;
"DQ<46>"
$PN"113"110;
"DQ<55>"
$PN"269"133;
"DQ<56>"
$PN"130"134;
"DQ<59>"
$PN"282"138;
"DQ<60>"
$PN"128"139;
"CKE<1>"
$PN"203"47;
"CK0N"
$PN"75"59;
"CB<0>"
$PN"49"48;
"CB<1>"
$PN"194"49;
"CB<2>"
$PN"56"50;
"CB<3>"
$PN"201"51;
"CB<4>"
$PN"47"52;
"CB<5>"
$PN"192"53;
"CB<6>"
$PN"54"54;
"A9"
$PN"66"115;
"A8"
$PN"68"116;
"A7"
$PN"211"117;
"A6"
$PN"69"118;
"A5"
$PN"213"119;
"A4"
$PN"214"120;
"A3"
$PN"71"121;
"A17"
$PN"234"23;
"A13"
$PN"232"26;
"A12"
$PN"65"122;
"A1"
$PN"72"123;
"A0"
$PN"79"55;
"C<2>"
$PN"235"37;
"DQ<28>"
$PN"36"95;
"DQ<29>"
$PN"181"96;
"S1_N"
$PN"89"56;
"S2_N_C<0>"
$PN"93"57;
"S3_N_C<1>"
$PN"237"62;
"CK0P"
$PN"74"60;
"CK1N"
$PN"219"61;
"BA<1>"
$PN"224"58;
%"SCONN288_H44441004"
"2","(0,4300)","0","mstr_sconn","I187";
;
CDS_SEC"2"
LOCATION"J1A1"
PART_NUMBER"H44441-004"
MATERIAL"SCONN"
PACK_TYPE"PIP"
BOM_COST"MEM"
CDS_LIB"mstr_sconn"
SEC_TYPE"PIP"
SEC"2"
CDS_LOCATION"J1A1"
ROOM"DDR4_CH_M";
"DQS17P"
$PN"51"176;
"DQS9P"
$PN"7"155;
"DQS9N"
$PN"8"156;
"DQS8P"
$PN"197"157;
"DQS8N"
$PN"196"158;
"DQS7P"
$PN"278"159;
"DQS7N"
$PN"277"160;
"DQS6P"
$PN"267"141;
"DQS6N"
$PN"266"142;
"DQS5P"
$PN"256"143;
"DQS5N"
$PN"255"144;
"DQS4P"
$PN"245"145;
"DQS4N"
$PN"244"146;
"DQS3P"
$PN"186"147;
"DQS3N"
$PN"185"148;
"DQS2P"
$PN"175"149;
"DQS2N"
$PN"174"150;
"DQS1P"
$PN"164"151;
"DQS1N"
$PN"163"152;
"DQS17N"
$PN"52"161;
"DQS16P"
$PN"132"162;
"DQS16N"
$PN"133"163;
"DQS15P"
$PN"121"164;
"DQS15N"
$PN"122"165;
"DQS14P"
$PN"110"166;
"DQS14N"
$PN"111"167;
"DQS13P"
$PN"99"168;
"DQS13N"
$PN"100"169;
"DQS12P"
$PN"40"170;
"DQS12N"
$PN"41"171;
"DQS11P"
$PN"29"172;
"DQS11N"
$PN"30"173;
"DQS10P"
$PN"18"174;
"DQS10N"
$PN"19"175;
"DQS0P"
$PN"153"153;
"DQS0N"
$PN"152"154;
%"P12V_NVDIMM_KLM"
"1","(300,3025)","0","mstr_symbols","I188";
;
VOLTAGE"12.0"
CDS_LIB"mstr_symbols"
BODY_TYPE"PLUMBING"
HDL_POWER"P12V_NVDIMM_KLM";
"G\NAC"19;
%"TAP"
"6","(900,3800)","2","mstr_standard","I19";
;
CDS_LIB"mstr_standard"
BODY_TYPE"PLUMBING"
HDL_TAP"TRUE";
"B \NAC \NWC"2;
"S \NAC"
BN"4"146;
%"TAP"
"6","(900,3700)","2","mstr_standard","I20";
;
CDS_LIB"mstr_standard"
BODY_TYPE"PLUMBING"
HDL_TAP"TRUE";
"B \NAC \NWC"2;
"S \NAC"
BN"3"148;
%"TAP"
"6","(900,3500)","2","mstr_standard","I21";
;
CDS_LIB"mstr_standard"
BODY_TYPE"PLUMBING"
HDL_TAP"TRUE";
"B \NAC \NWC"2;
"S \NAC"
BN"1"152;
%"TAP"
"6","(900,3600)","2","mstr_standard","I22";
;
CDS_LIB"mstr_standard"
BODY_TYPE"PLUMBING"
HDL_TAP"TRUE";
"B \NAC \NWC"2;
"S \NAC"
BN"2"150;
%"TAP"
"6","(900,3400)","2","mstr_standard","I23";
;
CDS_LIB"mstr_standard"
BODY_TYPE"PLUMBING"
HDL_TAP"TRUE";
"B \NAC \NWC"2;
"S \NAC"
BN"0"154;
%"GND"
"1","(1100,1150)","2","mstr_symbols","I26";
;
VOLTAGE"0"
BOM_COST"MEM"
SIZE"1B"
CDS_LIB"mstr_symbols"
BODY_TYPE"PLUMBING"
ROOM"DDR4_CH_D"
HDL_POWER"GND";
"A\NAC"20;
%"TAP"
"6","(700,5150)","2","mstr_standard","I27";
;
CDS_LIB"mstr_standard"
BODY_TYPE"PLUMBING"
HDL_TAP"TRUE";
"B \NAC \NWC"1;
"S \NAC"
BN"17"176;
%"TAP"
"6","(700,5050)","2","mstr_standard","I28";
;
CDS_LIB"mstr_standard"
BODY_TYPE"PLUMBING"
HDL_TAP"TRUE";
"B \NAC \NWC"1;
"S \NAC"
BN"16"162;
%"TAP"
"6","(700,4750)","2","mstr_standard","I29";
;
CDS_LIB"mstr_standard"
BODY_TYPE"PLUMBING"
HDL_TAP"TRUE";
"B \NAC \NWC"1;
"S \NAC"
BN"13"168;
%"TAP"
"6","(900,5100)","2","mstr_standard","I3";
;
CDS_LIB"mstr_standard"
BODY_TYPE"PLUMBING"
HDL_TAP"TRUE";
"B \NAC \NWC"2;
"S \NAC"
BN"17"161;
%"TAP"
"6","(700,4650)","2","mstr_standard","I30";
;
CDS_LIB"mstr_standard"
BODY_TYPE"PLUMBING"
HDL_TAP"TRUE";
"B \NAC \NWC"1;
"S \NAC"
BN"12"170;
%"TAP"
"6","(700,4550)","2","mstr_standard","I31";
;
CDS_LIB"mstr_standard"
BODY_TYPE"PLUMBING"
HDL_TAP"TRUE";
"B \NAC \NWC"1;
"S \NAC"
BN"11"172;
%"TAP"
"6","(700,4950)","2","mstr_standard","I32";
;
CDS_LIB"mstr_standard"
BODY_TYPE"PLUMBING"
HDL_TAP"TRUE";
"B \NAC \NWC"1;
"S \NAC"
BN"15"164;
%"TAP"
"6","(700,4850)","2","mstr_standard","I33";
;
CDS_LIB"mstr_standard"
BODY_TYPE"PLUMBING"
HDL_TAP"TRUE";
"B \NAC \NWC"1;
"S \NAC"
BN"14"166;
%"TAP"
"6","(-1750,4700)","2","mstr_standard","I35";
;
CDS_LIB"mstr_standard"
BODY_TYPE"PLUMBING"
HDL_TAP"TRUE";
"B \NAC \NWC"3;
"S \NAC"
BN"58"138;
%"TAP"
"6","(-1750,4900)","2","mstr_standard","I36";
;
CDS_LIB"mstr_standard"
BODY_TYPE"PLUMBING"
HDL_TAP"TRUE";
"B \NAC \NWC"3;
"S \NAC"
BN"62"140;
%"TAP"
"6","(-1750,4850)","2","mstr_standard","I37";
;
CDS_LIB"mstr_standard"
BODY_TYPE"PLUMBING"
HDL_TAP"TRUE";
"B \NAC \NWC"3;
"S \NAC"
BN"63"135;
%"TAP"
"6","(-1750,4800)","2","mstr_standard","I38";
;
CDS_LIB"mstr_standard"
BODY_TYPE"PLUMBING"
HDL_TAP"TRUE";
"B \NAC \NWC"3;
"S \NAC"
BN"60"136;
%"TAP"
"6","(-1750,4750)","2","mstr_standard","I39";
;
CDS_LIB"mstr_standard"
BODY_TYPE"PLUMBING"
HDL_TAP"TRUE";
"B \NAC \NWC"3;
"S \NAC"
BN"61"139;
%"TAP"
"6","(900,5000)","2","mstr_standard","I4";
;
CDS_LIB"mstr_standard"
BODY_TYPE"PLUMBING"
HDL_TAP"TRUE";
"B \NAC \NWC"2;
"S \NAC"
BN"16"163;
%"TAP"
"6","(-1750,4450)","2","mstr_standard","I40";
;
CDS_LIB"mstr_standard"
BODY_TYPE"PLUMBING"
HDL_TAP"TRUE";
"B \NAC \NWC"3;
"S \NAC"
BN"55"131;
%"TAP"
"6","(-1750,4600)","2","mstr_standard","I41";
;
CDS_LIB"mstr_standard"
BODY_TYPE"PLUMBING"
HDL_TAP"TRUE";
"B \NAC \NWC"3;
"S \NAC"
BN"56"132;
%"TAP"
"6","(-1750,4650)","2","mstr_standard","I42";
;
CDS_LIB"mstr_standard"
BODY_TYPE"PLUMBING"
HDL_TAP"TRUE";
"B \NAC \NWC"3;
"S \NAC"
BN"59"137;
%"TAP"
"6","(-1750,4500)","2","mstr_standard","I43";
;
CDS_LIB"mstr_standard"
BODY_TYPE"PLUMBING"
HDL_TAP"TRUE";
"B \NAC \NWC"3;
"S \NAC"
BN"54"133;
%"TAP"
"6","(-1750,4550)","2","mstr_standard","I44";
;
CDS_LIB"mstr_standard"
BODY_TYPE"PLUMBING"
HDL_TAP"TRUE";
"B \NAC \NWC"3;
"S \NAC"
BN"57"134;
%"TAP"
"6","(-1750,4200)","2","mstr_standard","I45";
;
CDS_LIB"mstr_standard"
BODY_TYPE"PLUMBING"
HDL_TAP"TRUE";
"B \NAC \NWC"3;
"S \NAC"
BN"48"126;
%"TAP"
"6","(-1750,4400)","2","mstr_standard","I46";
;
CDS_LIB"mstr_standard"
BODY_TYPE"PLUMBING"
HDL_TAP"TRUE";
"B \NAC \NWC"3;
"S \NAC"
BN"52"130;
%"TAP"
"6","(-1750,4350)","2","mstr_standard","I47";
;
CDS_LIB"mstr_standard"
BODY_TYPE"PLUMBING"
HDL_TAP"TRUE";
"B \NAC \NWC"3;
"S \NAC"
BN"53"129;
%"TAP"
"6","(-1750,4250)","2","mstr_standard","I48";
;
CDS_LIB"mstr_standard"
BODY_TYPE"PLUMBING"
HDL_TAP"TRUE";
"B \NAC \NWC"3;
"S \NAC"
BN"51"127;
%"TAP"
"6","(-1750,4300)","2","mstr_standard","I49";
;
CDS_LIB"mstr_standard"
BODY_TYPE"PLUMBING"
HDL_TAP"TRUE";
"B \NAC \NWC"3;
"S \NAC"
BN"50"128;
%"TAP"
"6","(900,4900)","2","mstr_standard","I5";
;
CDS_LIB"mstr_standard"
BODY_TYPE"PLUMBING"
HDL_TAP"TRUE";
"B \NAC \NWC"2;
"S \NAC"
BN"15"165;
%"TAP"
"6","(-1750,4100)","2","mstr_standard","I50";
;
CDS_LIB"mstr_standard"
BODY_TYPE"PLUMBING"
HDL_TAP"TRUE";
"B \NAC \NWC"3;
"S \NAC"
BN"46"124;
%"TAP"
"6","(-1750,4150)","2","mstr_standard","I51";
;
CDS_LIB"mstr_standard"
BODY_TYPE"PLUMBING"
HDL_TAP"TRUE";
"B \NAC \NWC"3;
"S \NAC"
BN"49"125;
%"TAP"
"6","(-1750,4050)","2","mstr_standard","I52";
;
CDS_LIB"mstr_standard"
BODY_TYPE"PLUMBING"
HDL_TAP"TRUE";
"B \NAC \NWC"3;
"S \NAC"
BN"47"110;
%"TAP"
"6","(-1750,3950)","2","mstr_standard","I53";
;
CDS_LIB"mstr_standard"
BODY_TYPE"PLUMBING"
HDL_TAP"TRUE";
"B \NAC \NWC"3;
"S \NAC"
BN"45"108;
%"TAP"
"6","(-1750,4000)","2","mstr_standard","I54";
;
CDS_LIB"mstr_standard"
BODY_TYPE"PLUMBING"
HDL_TAP"TRUE";
"B \NAC \NWC"3;
"S \NAC"
BN"44"109;
%"TAP"
"6","(700,4250)","2","mstr_standard","I55";
;
CDS_LIB"mstr_standard"
BODY_TYPE"PLUMBING"
HDL_TAP"TRUE";
"B \NAC \NWC"1;
"S \NAC"
BN"8"157;
%"TAP"
"6","(700,4150)","2","mstr_standard","I56";
;
CDS_LIB"mstr_standard"
BODY_TYPE"PLUMBING"
HDL_TAP"TRUE";
"B \NAC \NWC"1;
"S \NAC"
BN"7"159;
%"TAP"
"6","(700,4050)","2","mstr_standard","I57";
;
CDS_LIB"mstr_standard"
BODY_TYPE"PLUMBING"
HDL_TAP"TRUE";
"B \NAC \NWC"1;
"S \NAC"
BN"6"141;
%"TAP"
"6","(700,4350)","2","mstr_standard","I58";
;
CDS_LIB"mstr_standard"
BODY_TYPE"PLUMBING"
HDL_TAP"TRUE";
"B \NAC \NWC"1;
"S \NAC"
BN"9"155;
%"TAP"
"6","(700,4450)","2","mstr_standard","I59";
;
CDS_LIB"mstr_standard"
BODY_TYPE"PLUMBING"
HDL_TAP"TRUE";
"B \NAC \NWC"1;
"S \NAC"
BN"10"174;
%"TAP"
"6","(900,4800)","2","mstr_standard","I6";
;
CDS_LIB"mstr_standard"
BODY_TYPE"PLUMBING"
HDL_TAP"TRUE";
"B \NAC \NWC"2;
"S \NAC"
BN"14"167;
%"TAP"
"6","(700,3750)","2","mstr_standard","I60";
;
CDS_LIB"mstr_standard"
BODY_TYPE"PLUMBING"
HDL_TAP"TRUE";
"B \NAC \NWC"1;
"S \NAC"
BN"3"147;
%"TAP"
"6","(700,3550)","2","mstr_standard","I61";
;
CDS_LIB"mstr_standard"
BODY_TYPE"PLUMBING"
HDL_TAP"TRUE";
"B \NAC \NWC"1;
"S \NAC"
BN"1"151;
%"TAP"
"6","(700,3650)","2","mstr_standard","I62";
;
CDS_LIB"mstr_standard"
BODY_TYPE"PLUMBING"
HDL_TAP"TRUE";
"B \NAC \NWC"1;
"S \NAC"
BN"2"149;
%"TAP"
"6","(700,3950)","2","mstr_standard","I63";
;
CDS_LIB"mstr_standard"
BODY_TYPE"PLUMBING"
HDL_TAP"TRUE";
"B \NAC \NWC"1;
"S \NAC"
BN"5"143;
%"TAP"
"6","(700,3850)","2","mstr_standard","I64";
;
CDS_LIB"mstr_standard"
BODY_TYPE"PLUMBING"
HDL_TAP"TRUE";
"B \NAC \NWC"1;
"S \NAC"
BN"4"145;
%"TAP"
"6","(700,3450)","2","mstr_standard","I65";
;
CDS_LIB"mstr_standard"
BODY_TYPE"PLUMBING"
HDL_TAP"TRUE";
"B \NAC \NWC"1;
"S \NAC"
BN"0"153;
%"TAP"
"6","(-1750,3900)","2","mstr_standard","I66";
;
CDS_LIB"mstr_standard"
BODY_TYPE"PLUMBING"
HDL_TAP"TRUE";
"B \NAC \NWC"3;
"S \NAC"
BN"42"107;
%"TAP"
"6","(-1750,3850)","2","mstr_standard","I67";
;
CDS_LIB"mstr_standard"
BODY_TYPE"PLUMBING"
HDL_TAP"TRUE";
"B \NAC \NWC"3;
"S \NAC"
BN"43"106;
%"TAP"
"6","(-1750,3750)","2","mstr_standard","I68";
;
CDS_LIB"mstr_standard"
BODY_TYPE"PLUMBING"
HDL_TAP"TRUE";
"B \NAC \NWC"3;
"S \NAC"
BN"41"104;
%"TAP"
"6","(-1750,3800)","2","mstr_standard","I69";
;
CDS_LIB"mstr_standard"
BODY_TYPE"PLUMBING"
HDL_TAP"TRUE";
"B \NAC \NWC"3;
"S \NAC"
BN"40"105;
%"TAP"
"6","(900,4700)","2","mstr_standard","I7";
;
CDS_LIB"mstr_standard"
BODY_TYPE"PLUMBING"
HDL_TAP"TRUE";
"B \NAC \NWC"2;
"S \NAC"
BN"13"169;
%"TAP"
"6","(-1750,3700)","2","mstr_standard","I70";
;
CDS_LIB"mstr_standard"
BODY_TYPE"PLUMBING"
HDL_TAP"TRUE";
"B \NAC \NWC"3;
"S \NAC"
BN"38"27;
%"TAP"
"6","(-1750,3650)","2","mstr_standard","I71";
;
CDS_LIB"mstr_standard"
BODY_TYPE"PLUMBING"
HDL_TAP"TRUE";
"B \NAC \NWC"3;
"S \NAC"
BN"39"102;
%"TAP"
"6","(-1750,3600)","2","mstr_standard","I72";
;
CDS_LIB"mstr_standard"
BODY_TYPE"PLUMBING"
HDL_TAP"TRUE";
"B \NAC \NWC"3;
"S \NAC"
BN"36"103;
%"TAP"
"6","(-1750,3550)","2","mstr_standard","I73";
;
CDS_LIB"mstr_standard"
BODY_TYPE"PLUMBING"
HDL_TAP"TRUE";
"B \NAC \NWC"3;
"S \NAC"
BN"37"97;
%"TAP"
"6","(-1750,3500)","2","mstr_standard","I74";
;
CDS_LIB"mstr_standard"
BODY_TYPE"PLUMBING"
HDL_TAP"TRUE";
"B \NAC \NWC"3;
"S \NAC"
BN"34"98;
%"TAP"
"6","(-1750,3450)","2","mstr_standard","I75";
;
CDS_LIB"mstr_standard"
BODY_TYPE"PLUMBING"
HDL_TAP"TRUE";
"B \NAC \NWC"3;
"S \NAC"
BN"35"101;
%"TAP"
"6","(-1750,3400)","2","mstr_standard","I76";
;
CDS_LIB"mstr_standard"
BODY_TYPE"PLUMBING"
HDL_TAP"TRUE";
"B \NAC \NWC"3;
"S \NAC"
BN"32"100;
%"TAP"
"6","(-1750,3350)","2","mstr_standard","I77";
;
CDS_LIB"mstr_standard"
BODY_TYPE"PLUMBING"
HDL_TAP"TRUE";
"B \NAC \NWC"3;
"S \NAC"
BN"33"99;
%"TAP"
"6","(-1750,3200)","2","mstr_standard","I78";
;
CDS_LIB"mstr_standard"
BODY_TYPE"PLUMBING"
HDL_TAP"TRUE";
"B \NAC \NWC"3;
"S \NAC"
BN"28"96;
%"TAP"
"6","(-1750,3250)","2","mstr_standard","I79";
;
CDS_LIB"mstr_standard"
BODY_TYPE"PLUMBING"
HDL_TAP"TRUE";
"B \NAC \NWC"3;
"S \NAC"
BN"31"93;
%"TAP"
"6","(900,4600)","2","mstr_standard","I8";
;
CDS_LIB"mstr_standard"
BODY_TYPE"PLUMBING"
HDL_TAP"TRUE";
"B \NAC \NWC"2;
"S \NAC"
BN"12"171;
%"TAP"
"6","(-1750,3300)","2","mstr_standard","I80";
;
CDS_LIB"mstr_standard"
BODY_TYPE"PLUMBING"
HDL_TAP"TRUE";
"B \NAC \NWC"3;
"S \NAC"
BN"30"94;
%"TAP"
"6","(-1750,2900)","2","mstr_standard","I81";
;
CDS_LIB"mstr_standard"
BODY_TYPE"PLUMBING"
HDL_TAP"TRUE";
"B \NAC \NWC"3;
"S \NAC"
BN"22"89;
%"TAP"
"6","(-1750,3100)","2","mstr_standard","I82";
;
CDS_LIB"mstr_standard"
BODY_TYPE"PLUMBING"
HDL_TAP"TRUE";
"B \NAC \NWC"3;
"S \NAC"
BN"26"92;
%"TAP"
"6","(-1750,3150)","2","mstr_standard","I83";
;
CDS_LIB"mstr_standard"
BODY_TYPE"PLUMBING"
HDL_TAP"TRUE";
"B \NAC \NWC"3;
"S \NAC"
BN"29"95;
%"TAP"
"6","(-1750,3050)","2","mstr_standard","I84";
;
CDS_LIB"mstr_standard"
BODY_TYPE"PLUMBING"
HDL_TAP"TRUE";
"B \NAC \NWC"3;
"S \NAC"
BN"27"87;
%"TAP"
"6","(-1750,3000)","2","mstr_standard","I85";
;
CDS_LIB"mstr_standard"
BODY_TYPE"PLUMBING"
HDL_TAP"TRUE";
"B \NAC \NWC"3;
"S \NAC"
BN"24"91;
%"TAP"
"6","(-1750,2950)","2","mstr_standard","I86";
;
CDS_LIB"mstr_standard"
BODY_TYPE"PLUMBING"
HDL_TAP"TRUE";
"B \NAC \NWC"3;
"S \NAC"
BN"25"90;
%"TAP"
"6","(-1750,2650)","2","mstr_standard","I88";
;
CDS_LIB"mstr_standard"
BODY_TYPE"PLUMBING"
HDL_TAP"TRUE";
"B \NAC \NWC"3;
"S \NAC"
BN"19"83;
%"TAP"
"6","(-1750,2850)","2","mstr_standard","I89";
;
CDS_LIB"mstr_standard"
BODY_TYPE"PLUMBING"
HDL_TAP"TRUE";
"B \NAC \NWC"3;
"S \NAC"
BN"23"88;
%"PVTT_KLM"
"1","(-1250,2750)","0","mstr_symbols","I9";
;
VOLTAGE"0.6V"
BOM_COST"MEM"
CDS_LIB"mstr_symbols"
BODY_TYPE"PLUMBING"
ROOM"DDR4_CH_D"
HDL_POWER"PVTT_KLM";
"G\NAC"21;
%"TAP"
"6","(-1750,2800)","2","mstr_standard","I90";
;
CDS_LIB"mstr_standard"
BODY_TYPE"PLUMBING"
HDL_TAP"TRUE";
"B \NAC \NWC"3;
"S \NAC"
BN"20"86;
%"TAP"
"6","(-1750,2700)","2","mstr_standard","I91";
;
CDS_LIB"mstr_standard"
BODY_TYPE"PLUMBING"
HDL_TAP"TRUE";
"B \NAC \NWC"3;
"S \NAC"
BN"18"84;
%"TAP"
"6","(-1750,2750)","2","mstr_standard","I92";
;
CDS_LIB"mstr_standard"
BODY_TYPE"PLUMBING"
HDL_TAP"TRUE";
"B \NAC \NWC"3;
"S \NAC"
BN"21"85;
%"TAP"
"6","(-1750,2400)","2","mstr_standard","I93";
;
CDS_LIB"mstr_standard"
BODY_TYPE"PLUMBING"
HDL_TAP"TRUE";
"B \NAC \NWC"3;
"S \NAC"
BN"12"78;
%"TAP"
"6","(-1750,2550)","2","mstr_standard","I94";
;
CDS_LIB"mstr_standard"
BODY_TYPE"PLUMBING"
HDL_TAP"TRUE";
"B \NAC \NWC"3;
"S \NAC"
BN"17"80;
%"TAP"
"6","(-1750,2600)","2","mstr_standard","I95";
;
CDS_LIB"mstr_standard"
BODY_TYPE"PLUMBING"
HDL_TAP"TRUE";
"B \NAC \NWC"3;
"S \NAC"
BN"16"82;
%"TAP"
"6","(-1750,2450)","2","mstr_standard","I96";
;
CDS_LIB"mstr_standard"
BODY_TYPE"PLUMBING"
HDL_TAP"TRUE";
"B \NAC \NWC"3;
"S \NAC"
BN"15"79;
%"TAP"
"6","(-1750,2500)","2","mstr_standard","I97";
;
CDS_LIB"mstr_standard"
BODY_TYPE"PLUMBING"
HDL_TAP"TRUE";
"B \NAC \NWC"3;
"S \NAC"
BN"14"77;
%"TAP"
"6","(-1750,2150)","2","mstr_standard","I98";
;
CDS_LIB"mstr_standard"
BODY_TYPE"PLUMBING"
HDL_TAP"TRUE";
"B \NAC \NWC"3;
"S \NAC"
BN"9"73;
%"TAP"
"6","(-1750,2250)","2","mstr_standard","I99";
;
CDS_LIB"mstr_standard"
BODY_TYPE"PLUMBING"
HDL_TAP"TRUE";
"B \NAC \NWC"3;
"S \NAC"
BN"11"76;
END.
